# S9S_MB_2U (Grand Teton) — schematic netlist excerpt (pin names and nets, part order shuffled) for the footprints in the layout excerpt that follows; sources: Cadence DE-HDL packaged netlist, KiCad conversion of 03242023_DA0F0TMBIJ0_F0T_Motherboard_J_brd_V01_OCP.brd

PC813  Q_CAP  1UF 16V 10% X6S  pkg C0402  page 278 : A = PVCCD_HV_CPU0_ISENSE_N ; B = PVCCD_HV_CPU0_ISENSE_P
R1676  Q_RES  1K 1% EMPTY  pkg 0402LF  page 182 : A = FM_PCIE_EV_BIF_EN ; B = GND

(kicad_pcb
	(version 20260206)
	(generator "pcbnew")
	(generator_version "10.0")
	(general
		(thickness 1.6)
		(legacy_teardrops no)
	)
	(paper "A4")
	(title_block
		(title "03242023_DA0F0TMBIJ0_F0T_Motherboard_J_brd_V01_OCP.brd")
		(comment 1 "Grand Teton / footprints 5568-5569 of 6105")
	)
	(layers
		(0 "F.Cu" signal "TOP")
		(4 "In1.Cu" signal "GND")
		(6 "In2.Cu" signal "IN1")
		(8 "In3.Cu" signal "GND1")
		(10 "In4.Cu" signal "IN2")
		(12 "In5.Cu" signal "GND2")
		(14 "In6.Cu" signal "IN3")
		(16 "In7.Cu" signal "GND3")
		(18 "In8.Cu" signal "VCC")
		(20 "In9.Cu" signal "VCC1")
		(22 "In10.Cu" signal "GND4")
		(24 "In11.Cu" signal "IN4")
		(26 "In12.Cu" signal "GND5")
		(28 "In13.Cu" signal "IN5")
		(30 "In14.Cu" signal "GND6")
		(32 "In15.Cu" signal "IN6")
		(34 "In16.Cu" signal "GND7")
		(2 "B.Cu" signal "BOTTOM")
		(9 "F.Adhes" user "F.Adhesive")
		(11 "B.Adhes" user "B.Adhesive")
		(13 "F.Paste" user "Package Geometry/Pastemask Top")
		(15 "B.Paste" user "Package Geometry/Pastemask Bottom")
		(5 "F.SilkS" user "Ref Des/Silkscreen Top")
		(7 "B.SilkS" user "Ref Des/Silkscreen Bottom")
		(1 "F.Mask" user "Board Geometry/Soldermask Top")
		(3 "B.Mask" user "Board Geometry/Soldermask Bottom")
		(17 "Dwgs.User" user "User.Drawings")
		(19 "Cmts.User" user "User.Comments")
		(21 "Eco1.User" user "User.Eco1")
		(23 "Eco2.User" user "User.Eco2")
		(25 "Edge.Cuts" user "Board Geometry/Outline")
		(27 "Margin" user)
		(31 "F.CrtYd" user "Package Geometry/Place Bound Top")
		(29 "B.CrtYd" user "Package Geometry/Place Bound Bottom")
		(35 "F.Fab" user "Ref Des/Assembly Top")
		(33 "B.Fab" user "Ref Des/Assembly Bottom")
	)
	(footprint ""
		(layer "B.Cu")
		(at 326.16648 -61.758068 -90)
		(property "Reference" "R1676"
			(at 0 0 90)
			(layer "B.SilkS")
			(hide yes)
			(effects
				(font
					(size 1.27 1.27)
				)
				(justify mirror)
			)
		)
		(property "Value" ""
			(at 0 0 90)
			(layer "B.Fab")
			(effects
				(font
					(size 1.27 1.27)
				)
				(justify mirror)
			)
		)
		(duplicate_pad_numbers_are_jumpers no)
		(fp_line
			(start -0.7874 0.4064)
			(end 0.7874 0.4064)
			(stroke
				(width 0.1524)
				(type default)
			)
			(layer "B.SilkS")
		)
		(fp_line
			(start 0.7874 0.4064)
			(end 0.7874 -0.4064)
			(stroke
				(width 0.1524)
				(type default)
			)
			(layer "B.SilkS")
		)
		(fp_line
			(start -0.7874 -0.4064)
			(end -0.7874 0.4064)
			(stroke
				(width 0.1524)
				(type default)
			)
			(layer "B.SilkS")
		)
		(fp_line
			(start 0.7874 -0.4064)
			(end -0.7874 -0.4064)
			(stroke
				(width 0.1524)
				(type default)
			)
			(layer "B.SilkS")
		)
		(fp_line
			(start -0.67945 0.3048)
			(end -0.120396 0.3048)
			(stroke
				(width 0.1)
				(type default)
			)
			(layer "B.Fab")
		)
		(fp_line
			(start -0.120396 0.3048)
			(end -0.120396 0.2794)
			(stroke
				(width 0.1)
				(type default)
			)
			(layer "B.Fab")
		)
		(fp_line
			(start 0.12065 0.3048)
			(end 0.67945 0.3048)
			(stroke
				(width 0.1)
				(type default)
			)
			(layer "B.Fab")
		)
		(fp_line
			(start 0.67945 0.3048)
			(end 0.67945 -0.305054)
			(stroke
				(width 0.1)
				(type default)
			)
			(layer "B.Fab")
		)
		(fp_line
			(start -0.120396 0.2794)
			(end 0.12065 0.2794)
			(stroke
				(width 0.1)
				(type default)
			)
			(layer "B.Fab")
		)
		(fp_line
			(start 0.12065 0.2794)
			(end 0.12065 0.3048)
			(stroke
				(width 0.1)
				(type default)
			)
			(layer "B.Fab")
		)
		(fp_line
			(start -0.12065 -0.2794)
			(end -0.12065 -0.3048)
			(stroke
				(width 0.1)
				(type default)
			)
			(layer "B.Fab")
		)
		(fp_line
			(start 0.12065 -0.2794)
			(end -0.12065 -0.2794)
			(stroke
				(width 0.1)
				(type default)
			)
			(layer "B.Fab")
		)
		(fp_line
			(start -0.67945 -0.3048)
			(end -0.67945 0.3048)
			(stroke
				(width 0.1)
				(type default)
			)
			(layer "B.Fab")
		)
		(fp_line
			(start -0.12065 -0.3048)
			(end -0.67945 -0.3048)
			(stroke
				(width 0.1)
				(type default)
			)
			(layer "B.Fab")
		)
		(fp_line
			(start 0.12065 -0.305054)
			(end 0.12065 -0.2794)
			(stroke
				(width 0.1)
				(type default)
			)
			(layer "B.Fab")
		)
		(fp_line
			(start 0.67945 -0.305054)
			(end 0.12065 -0.305054)
			(stroke
				(width 0.1)
				(type default)
			)
			(layer "B.Fab")
		)
		(pad "1" smd circle
			(at 0.40005 0 90)
			(size 0 0)
			(layers "B.Cu" "B.Mask" "B.Paste")
			(net "FM_PCIE_EV_BIF_EN")
		)
		(pad "2" smd circle
			(at -0.40005 0 90)
			(size 0 0)
			(layers "B.Cu" "B.Mask" "B.Paste")
			(net "GND")
		)
	)
	(footprint ""
		(layer "B.Cu")
		(at 428.164244 -122.085862 -90)
		(property "Reference" "PC813"
			(at 0 0 90)
			(layer "B.SilkS")
			(hide yes)
			(effects
				(font
					(size 1.27 1.27)
				)
				(justify mirror)
			)
		)
		(property "Value" ""
			(at 0 0 90)
			(layer "B.Fab")
			(effects
				(font
					(size 1.27 1.27)
				)
				(justify mirror)
			)
		)
		(duplicate_pad_numbers_are_jumpers no)
		(fp_line
			(start -0.7874 0.4064)
			(end 0.7874 0.4064)
			(stroke
				(width 0.1524)
				(type default)
			)
			(layer "B.SilkS")
		)
		(fp_line
			(start 0.7874 0.4064)
			(end 0.7874 -0.4064)
			(stroke
				(width 0.1524)
				(type default)
			)
			(layer "B.SilkS")
		)
		(fp_line
			(start -0.7874 -0.4064)
			(end -0.7874 0.4064)
			(stroke
				(width 0.1524)
				(type default)
			)
			(layer "B.SilkS")
		)
		(fp_line
			(start 0.7874 -0.4064)
			(end -0.7874 -0.4064)
			(stroke
				(width 0.1524)
				(type default)
			)
			(layer "B.SilkS")
		)
		(fp_line
			(start -0.67945 0.3048)
			(end -0.120396 0.3048)
			(stroke
				(width 0.1)
				(type default)
			)
			(layer "B.Fab")
		)
		(fp_line
			(start -0.120396 0.3048)
			(end -0.120396 0.2794)
			(stroke
				(width 0.1)
				(type default)
			)
			(layer "B.Fab")
		)
		(fp_line
			(start 0.12065 0.3048)
			(end 0.67945 0.3048)
			(stroke
				(width 0.1)
				(type default)
			)
			(layer "B.Fab")
		)
		(fp_line
			(start 0.67945 0.3048)
			(end 0.67945 -0.305054)
			(stroke
				(width 0.1)
				(type default)
			)
			(layer "B.Fab")
		)
		(fp_line
			(start -0.120396 0.2794)
			(end 0.12065 0.2794)
			(stroke
				(width 0.1)
				(type default)
			)
			(layer "B.Fab")
		)
		(fp_line
			(start 0.12065 0.2794)
			(end 0.12065 0.3048)
			(stroke
				(width 0.1)
				(type default)
			)
			(layer "B.Fab")
		)
		(fp_line
			(start -0.12065 -0.2794)
			(end -0.12065 -0.3048)
			(stroke
				(width 0.1)
				(type default)
			)
			(layer "B.Fab")
		)
		(fp_line
			(start 0.12065 -0.2794)
			(end -0.12065 -0.2794)
			(stroke
				(width 0.1)
				(type default)
			)
			(layer "B.Fab")
		)
		(fp_line
			(start -0.67945 -0.3048)
			(end -0.67945 0.3048)
			(stroke
				(width 0.1)
				(type default)
			)
			(layer "B.Fab")
		)
		(fp_line
			(start -0.12065 -0.3048)
			(end -0.67945 -0.3048)
			(stroke
				(width 0.1)
				(type default)
			)
			(layer "B.Fab")
		)
		(fp_line
			(start 0.12065 -0.305054)
			(end 0.12065 -0.2794)
			(stroke
				(width 0.1)
				(type default)
			)
			(layer "B.Fab")
		)
		(fp_line
			(start 0.67945 -0.305054)
			(end 0.12065 -0.305054)
			(stroke
				(width 0.1)
				(type default)
			)
			(layer "B.Fab")
		)
		(pad "1" smd circle
			(at 0.40005 0 90)
			(size 0 0)
			(layers "B.Cu" "B.Mask" "B.Paste")
			(net "PVCCD_HV_CPU0_ISENSE_N")
		)
		(pad "2" smd circle
			(at -0.40005 0 90)
			(size 0 0)
			(layers "B.Cu" "B.Mask" "B.Paste")
			(net "PVCCD_HV_CPU0_ISENSE_P")
		)
	)
)
